# T6G (Grand Teton) — schematic netlist excerpt (pin names and nets, part order shuffled) for the footprints in the layout excerpt that follows; sources: Cadence DE-HDL packaged netlist, KiCad conversion of 04192023_DAF0TMB3IC0_F0TG_MB_C_brd_V02_OCP.brd

U8006  AP331AWG7  AP331AWG-7 EMPTY  pkg SOT25  page 267
  \in-\  = OC_P2V5_COMP
  GND  = GND
  \in+\  = HSC_OC_VOL
  OUTPUT  = HSC_D_OC_R2
  VCC  = P12V_AUX

PR12  Q_RES  0 5% CHIP  pkg 0402LF  page 217 : A = NC_PVDDCR_CPU1_P1_IMON8 ; B = GND
C1018  Q_CAP  1UF 4V 20% X6S  pkg 0201  page 312 : A = P0V9_CPU0_RT3_2A_2D ; B = GND

(kicad_pcb
	(version 20260206)
	(generator "pcbnew")
	(generator_version "10.0")
	(general
		(thickness 1.6)
		(legacy_teardrops no)
	)
	(paper "A4")
	(title_block
		(title "04192023_DAF0TMB3IC0_F0TG_MB_C_brd_V02_OCP.brd")
		(comment 1 "Grand Teton / footprints 6170-6172 of 8354")
	)
	(layers
		(0 "F.Cu" signal "TOP")
		(4 "In1.Cu" signal "GND")
		(6 "In2.Cu" signal "IN1")
		(8 "In3.Cu" signal "GND1")
		(10 "In4.Cu" signal "IN2")
		(12 "In5.Cu" signal "GND2")
		(14 "In6.Cu" signal "IN3")
		(16 "In7.Cu" signal "GND3")
		(18 "In8.Cu" signal "VCC")
		(20 "In9.Cu" signal "VCC1")
		(22 "In10.Cu" signal "GND4")
		(24 "In11.Cu" signal "IN4")
		(26 "In12.Cu" signal "GND5")
		(28 "In13.Cu" signal "IN5")
		(30 "In14.Cu" signal "GND6")
		(32 "In15.Cu" signal "IN6")
		(34 "In16.Cu" signal "GND7")
		(2 "B.Cu" signal "BOTTOM")
		(9 "F.Adhes" user "F.Adhesive")
		(11 "B.Adhes" user "B.Adhesive")
		(13 "F.Paste" user "Package Geometry/Pastemask Top")
		(15 "B.Paste" user "Package Geometry/Pastemask Bottom")
		(5 "F.SilkS" user "Ref Des/Silkscreen Top")
		(7 "B.SilkS" user "Ref Des/Silkscreen Bottom")
		(1 "F.Mask" user "Board Geometry/Soldermask Top")
		(3 "B.Mask" user "Board Geometry/Soldermask Bottom")
		(17 "Dwgs.User" user "User.Drawings")
		(19 "Cmts.User" user "User.Comments")
		(21 "Eco1.User" user "User.Eco1")
		(23 "Eco2.User" user "User.Eco2")
		(25 "Edge.Cuts" user "Board Geometry/Outline")
		(27 "Margin" user)
		(31 "F.CrtYd" user "Package Geometry/Place Bound Top")
		(29 "B.CrtYd" user "Package Geometry/Place Bound Bottom")
		(35 "F.Fab" user "Ref Des/Assembly Top")
		(33 "B.Fab" user "Ref Des/Assembly Bottom")
	)
	(footprint ""
		(layer "B.Cu")
		(at 383.67843 -395.148562 90)
		(property "Reference" "C1018"
			(at 0 0 90)
			(layer "B.SilkS")
			(hide yes)
			(effects
				(font
					(size 1.27 1.27)
				)
				(justify mirror)
			)
		)
		(property "Value" ""
			(at 0 0 90)
			(layer "B.Fab")
			(effects
				(font
					(size 1.27 1.27)
				)
				(justify mirror)
			)
		)
		(duplicate_pad_numbers_are_jumpers no)
		(fp_line
			(start 0.299974 -0.150114)
			(end -0.299974 -0.150114)
			(stroke
				(width 0.1)
				(type default)
			)
			(layer "B.Fab")
		)
		(fp_line
			(start -0.299974 -0.150114)
			(end -0.299974 0.150114)
			(stroke
				(width 0.1)
				(type default)
			)
			(layer "B.Fab")
		)
		(fp_line
			(start 0.299974 0.150114)
			(end 0.299974 -0.150114)
			(stroke
				(width 0.1)
				(type default)
			)
			(layer "B.Fab")
		)
		(fp_line
			(start -0.299974 0.150114)
			(end 0.299974 0.150114)
			(stroke
				(width 0.1)
				(type default)
			)
			(layer "B.Fab")
		)
		(pad "1" smd rect
			(at 0.2667 0 270)
			(size 0.3048 0.381)
			(layers "B.Cu" "B.Mask" "B.Paste")
			(net "P0V9_CPU0_RT3_2A_2D")
		)
		(pad "2" smd rect
			(at -0.2667 0 270)
			(size 0.3048 0.381)
			(layers "B.Cu" "B.Mask" "B.Paste")
			(net "GND")
		)
	)
	(footprint ""
		(layer "B.Cu")
		(at 187.325 -426.212 -90)
		(property "Reference" "U8006"
			(at -0.208534 -6.062472 270)
			(unlocked yes)
			(layer "B.SilkS")
			(effects
				(font
					(size 0.7874 0.5842)
					(thickness 0.1524)
				)
				(justify mirror)
			)
		)
		(property "Value" ""
			(at 0 0 90)
			(layer "B.Fab")
			(effects
				(font
					(size 1.27 1.27)
				)
				(justify mirror)
			)
		)
		(duplicate_pad_numbers_are_jumpers no)
		(fp_line
			(start -2.032 1.549908)
			(end 2.032 1.549908)
			(stroke
				(width 0.1524)
				(type default)
			)
			(layer "B.SilkS")
		)
		(fp_line
			(start 2.032 1.549908)
			(end 2.032 -1.549908)
			(stroke
				(width 0.1524)
				(type default)
			)
			(layer "B.SilkS")
		)
		(fp_line
			(start 0 -0.762)
			(end -0.508 -1.549908)
			(stroke
				(width 0.1524)
				(type default)
			)
			(layer "B.SilkS")
		)
		(fp_line
			(start -2.032 -1.549908)
			(end -2.032 1.549908)
			(stroke
				(width 0.1524)
				(type default)
			)
			(layer "B.SilkS")
		)
		(fp_line
			(start -0.508 -1.549908)
			(end -2.032 -1.549908)
			(stroke
				(width 0.1524)
				(type default)
			)
			(layer "B.SilkS")
		)
		(fp_line
			(start 0.508 -1.549908)
			(end 0 -0.762)
			(stroke
				(width 0.1524)
				(type default)
			)
			(layer "B.SilkS")
		)
		(fp_line
			(start 2.032 -1.549908)
			(end 0.508 -1.549908)
			(stroke
				(width 0.1524)
				(type default)
			)
			(layer "B.SilkS")
		)
		(fp_poly
			(pts
				(xy 2.036572 -2.90957) (xy 2.864358 -2.320544) (xy 1.861566 -1.787144)
			)
			(stroke
				(width 0)
				(type default)
			)
			(fill yes)
			(layer "B.SilkS")
		)
		(fp_line
			(start -0.849884 1.549908)
			(end 0.849884 1.549908)
			(stroke
				(width 0.1)
				(type default)
			)
			(layer "B.Fab")
		)
		(fp_line
			(start 0.849884 1.549908)
			(end 0.849884 -1.549908)
			(stroke
				(width 0.1)
				(type default)
			)
			(layer "B.Fab")
		)
		(fp_line
			(start -0.849884 -1.549908)
			(end -0.849884 1.549908)
			(stroke
				(width 0.1)
				(type default)
			)
			(layer "B.Fab")
		)
		(fp_line
			(start 0.849884 -1.549908)
			(end -0.849884 -1.549908)
			(stroke
				(width 0.1)
				(type default)
			)
			(layer "B.Fab")
		)
		(fp_poly
			(pts
				(xy 3.2004 -1.45796) (xy 3.2004 -0.44196) (xy 2.1844 -0.94996)
			)
			(stroke
				(width 0)
				(type default)
			)
			(fill yes)
			(layer "B.Fab")
		)
		(pad "1" smd rect
			(at 1.35001 -0.94996 180)
			(size 0.6096 1.0668)
			(layers "B.Cu" "B.Mask" "B.Paste")
			(net "OC_P2V5_COMP")
		)
		(pad "2" smd rect
			(at 1.35001 0 180)
			(size 0.6096 1.0668)
			(layers "B.Cu" "B.Mask" "B.Paste")
			(net "GND")
		)
		(pad "3" smd rect
			(at 1.35001 0.94996 180)
			(size 0.6096 1.0668)
			(layers "B.Cu" "B.Mask" "B.Paste")
			(net "HSC_OC_VOL")
		)
		(pad "4" smd rect
			(at -1.35001 0.94996 180)
			(size 0.6096 1.0668)
			(layers "B.Cu" "B.Mask" "B.Paste")
			(net "HSC_D_OC_R2")
		)
		(pad "5" smd rect
			(at -1.35001 -0.94996 180)
			(size 0.6096 1.0668)
			(layers "B.Cu" "B.Mask" "B.Paste")
			(net "P12V_AUX")
		)
	)
	(footprint ""
		(layer "B.Cu")
		(at 31.623 -361.569 -90)
		(property "Reference" "PR12"
			(at 0 0 90)
			(layer "B.SilkS")
			(hide yes)
			(effects
				(font
					(size 1.27 1.27)
				)
				(justify mirror)
			)
		)
		(property "Value" ""
			(at 0 0 90)
			(layer "B.Fab")
			(effects
				(font
					(size 1.27 1.27)
				)
				(justify mirror)
			)
		)
		(duplicate_pad_numbers_are_jumpers no)
		(fp_line
			(start -0.7874 0.4064)
			(end 0.7874 0.4064)
			(stroke
				(width 0.1524)
				(type default)
			)
			(layer "B.SilkS")
		)
		(fp_line
			(start 0.7874 0.4064)
			(end 0.7874 -0.4064)
			(stroke
				(width 0.1524)
				(type default)
			)
			(layer "B.SilkS")
		)
		(fp_line
			(start -0.7874 -0.4064)
			(end -0.7874 0.4064)
			(stroke
				(width 0.1524)
				(type default)
			)
			(layer "B.SilkS")
		)
		(fp_line
			(start 0.7874 -0.4064)
			(end -0.7874 -0.4064)
			(stroke
				(width 0.1524)
				(type default)
			)
			(layer "B.SilkS")
		)
		(fp_line
			(start -0.67945 0.3048)
			(end -0.120396 0.3048)
			(stroke
				(width 0.1)
				(type default)
			)
			(layer "B.Fab")
		)
		(fp_line
			(start -0.120396 0.3048)
			(end -0.120396 0.2794)
			(stroke
				(width 0.1)
				(type default)
			)
			(layer "B.Fab")
		)
		(fp_line
			(start 0.12065 0.3048)
			(end 0.67945 0.3048)
			(stroke
				(width 0.1)
				(type default)
			)
			(layer "B.Fab")
		)
		(fp_line
			(start 0.67945 0.3048)
			(end 0.67945 -0.305054)
			(stroke
				(width 0.1)
				(type default)
			)
			(layer "B.Fab")
		)
		(fp_line
			(start -0.120396 0.2794)
			(end 0.12065 0.2794)
			(stroke
				(width 0.1)
				(type default)
			)
			(layer "B.Fab")
		)
		(fp_line
			(start 0.12065 0.2794)
			(end 0.12065 0.3048)
			(stroke
				(width 0.1)
				(type default)
			)
			(layer "B.Fab")
		)
		(fp_line
			(start -0.12065 -0.2794)
			(end -0.12065 -0.3048)
			(stroke
				(width 0.1)
				(type default)
			)
			(layer "B.Fab")
		)
		(fp_line
			(start 0.12065 -0.2794)
			(end -0.12065 -0.2794)
			(stroke
				(width 0.1)
				(type default)
			)
			(layer "B.Fab")
		)
		(fp_line
			(start -0.67945 -0.3048)
			(end -0.67945 0.3048)
			(stroke
				(width 0.1)
				(type default)
			)
			(layer "B.Fab")
		)
		(fp_line
			(start -0.12065 -0.3048)
			(end -0.67945 -0.3048)
			(stroke
				(width 0.1)
				(type default)
			)
			(layer "B.Fab")
		)
		(fp_line
			(start 0.12065 -0.305054)
			(end 0.12065 -0.2794)
			(stroke
				(width 0.1)
				(type default)
			)
			(layer "B.Fab")
		)
		(fp_line
			(start 0.67945 -0.305054)
			(end 0.12065 -0.305054)
			(stroke
				(width 0.1)
				(type default)
			)
			(layer "B.Fab")
		)
		(pad "1" smd circle
			(at 0.40005 0 90)
			(size 0 0)
			(layers "B.Cu" "B.Mask" "B.Paste")
			(net "NC_PVDDCR_CPU1_P1_IMON8")
		)
		(pad "2" smd circle
			(at -0.40005 0 90)
			(size 0 0)
			(layers "B.Cu" "B.Mask" "B.Paste")
			(net "GND")
		)
	)
)
